#ISCELL
  mstr_misc dns *
  *
#ISCELL
  pure_quanta quanta_title_block_c *
  *
#ISCELL
  standard offpage *
  page42_i12
#CELL
  pure_quanta q_res *
  page42_i13
#ISCELL
  standard offpage *
  page42_i26
#CELL
  pure_quanta q_res *
  page42_i27
#ISCELL
  standard offpage *
  page42_i28
#CELL
  pure_quanta q_res *
  page42_i29
#ISCELL
  logical_power universal_power *
  page42_i3
#ISCELL
  standard offpage *
  page42_i36
#CELL
  pure_quanta q_res *
  page42_i37
#ISCELL
  standard offpage *
  page42_i38
#CELL
  pure_quanta q_res *
  page42_i39
#ISCELL
  standard offpage *
  page42_i52
#CELL
  pure_quanta q_res *
  page42_i53
#ISCELL
  logical_power universal_power *
  page42_i54
#ISCELL
  standard offpage *
  page42_i55
#CELL
  pure_quanta q_res *
  page42_i56
#ISCELL
  logical_power universal_gnd *
  page42_i57
#CELL
  pure_quanta q_res *
  page42_i58
#ISCELL
  standard offpage *
  page42_i6
#ISCELL
  standard offpage *
  page42_i60
#CELL
  pure_quanta q_res *
  page42_i61
#ISCELL
  standard offpage *
  page42_i62
#CELL
  pure_quanta q_res *
  page42_i63
#ISCELL
  standard offpage *
  page42_i64
#CELL
  pure_quanta q_res *
  page42_i65
#ISCELL
  standard offpage *
  page42_i66
#CELL
  pure_quanta q_res *
  page42_i67
#CELL
  pure_quanta q_res *
  page42_i7
